# SCM (Grand Teton) — schematic netlist excerpt (pin names and nets, part order shuffled) for the footprints in the layout excerpt that follows; sources: Cadence DE-HDL packaged netlist, KiCad conversion of 12092022_DA0F0TMDCD0_F0T_Management_Board_D_brd_V3_OCP.brd

C85  Q_CAP  0.1UF 25V 10% X7R  pkg 0402  page 16 : A = P3V3_RGM ; B = GND
R22  Q_RES  150 1% CHIP  pkg 0402LF  page 15 : A = V_DACB_R ; B = GND

(kicad_pcb
	(version 20260206)
	(generator "pcbnew")
	(generator_version "10.0")
	(general
		(thickness 1.6)
		(legacy_teardrops no)
	)
	(paper "A4")
	(title_block
		(title "12092022_DA0F0TMDCD0_F0T_Management_Board_D_brd_V3_OCP.brd")
		(comment 1 "Grand Teton / footprints 1335-1337 of 1440")
	)
	(layers
		(0 "F.Cu" signal "TOP")
		(4 "In1.Cu" signal "GND")
		(6 "In2.Cu" signal "IN1")
		(8 "In3.Cu" signal "GND1")
		(10 "In4.Cu" signal "IN2")
		(12 "In5.Cu" signal "VCC")
		(14 "In6.Cu" signal "VCC1")
		(16 "In7.Cu" signal "IN3")
		(18 "In8.Cu" signal "GND2")
		(20 "In9.Cu" signal "IN4")
		(22 "In10.Cu" signal "GND3")
		(2 "B.Cu" signal "BOTTOM")
		(9 "F.Adhes" user "F.Adhesive")
		(11 "B.Adhes" user "B.Adhesive")
		(13 "F.Paste" user "Package Geometry/Pastemask Top")
		(15 "B.Paste" user "Package Geometry/Pastemask Bottom")
		(5 "F.SilkS" user "Ref Des/Silkscreen Top")
		(7 "B.SilkS" user "Ref Des/Silkscreen Bottom")
		(1 "F.Mask" user "Board Geometry/Soldermask Top")
		(3 "B.Mask" user "Board Geometry/Soldermask Bottom")
		(17 "Dwgs.User" user "User.Drawings")
		(19 "Cmts.User" user "User.Comments")
		(21 "Eco1.User" user "User.Eco1")
		(23 "Eco2.User" user "User.Eco2")
		(25 "Edge.Cuts" user "Board Geometry/Outline")
		(27 "Margin" user)
		(31 "F.CrtYd" user "Package Geometry/Place Bound Top")
		(29 "B.CrtYd" user "Package Geometry/Place Bound Bottom")
		(35 "F.Fab" user "Ref Des/Assembly Top")
		(33 "B.Fab" user "Ref Des/Assembly Bottom")
	)
	(footprint ""
		(layer "B.Cu")
		(at 56.331358 -46.200568)
		(property "Reference" "C85"
			(at 0 0 0)
			(layer "B.SilkS")
			(hide yes)
			(effects
				(font
					(size 1.27 1.27)
				)
				(justify mirror)
			)
		)
		(property "Value" ""
			(at 0 0 0)
			(layer "B.Fab")
			(effects
				(font
					(size 1.27 1.27)
				)
				(justify mirror)
			)
		)
		(duplicate_pad_numbers_are_jumpers no)
		(fp_line
			(start -0.7874 -0.4064)
			(end -0.7874 0.4064)
			(stroke
				(width 0.1524)
				(type default)
			)
			(layer "B.SilkS")
		)
		(fp_line
			(start -0.7874 0.4064)
			(end 0.7874 0.4064)
			(stroke
				(width 0.1524)
				(type default)
			)
			(layer "B.SilkS")
		)
		(fp_line
			(start 0.7874 -0.4064)
			(end -0.7874 -0.4064)
			(stroke
				(width 0.1524)
				(type default)
			)
			(layer "B.SilkS")
		)
		(fp_line
			(start 0.7874 0.4064)
			(end 0.7874 -0.4064)
			(stroke
				(width 0.1524)
				(type default)
			)
			(layer "B.SilkS")
		)
		(fp_line
			(start -0.67945 -0.3048)
			(end -0.67945 0.3048)
			(stroke
				(width 0.1)
				(type default)
			)
			(layer "B.Fab")
		)
		(fp_line
			(start -0.67945 0.3048)
			(end -0.120396 0.3048)
			(stroke
				(width 0.1)
				(type default)
			)
			(layer "B.Fab")
		)
		(fp_line
			(start -0.12065 -0.3048)
			(end -0.67945 -0.3048)
			(stroke
				(width 0.1)
				(type default)
			)
			(layer "B.Fab")
		)
		(fp_line
			(start -0.12065 -0.2794)
			(end -0.12065 -0.3048)
			(stroke
				(width 0.1)
				(type default)
			)
			(layer "B.Fab")
		)
		(fp_line
			(start -0.120396 0.2794)
			(end 0.12065 0.2794)
			(stroke
				(width 0.1)
				(type default)
			)
			(layer "B.Fab")
		)
		(fp_line
			(start -0.120396 0.3048)
			(end -0.120396 0.2794)
			(stroke
				(width 0.1)
				(type default)
			)
			(layer "B.Fab")
		)
		(fp_line
			(start 0.12065 -0.305054)
			(end 0.12065 -0.2794)
			(stroke
				(width 0.1)
				(type default)
			)
			(layer "B.Fab")
		)
		(fp_line
			(start 0.12065 -0.2794)
			(end -0.12065 -0.2794)
			(stroke
				(width 0.1)
				(type default)
			)
			(layer "B.Fab")
		)
		(fp_line
			(start 0.12065 0.2794)
			(end 0.12065 0.3048)
			(stroke
				(width 0.1)
				(type default)
			)
			(layer "B.Fab")
		)
		(fp_line
			(start 0.12065 0.3048)
			(end 0.67945 0.3048)
			(stroke
				(width 0.1)
				(type default)
			)
			(layer "B.Fab")
		)
		(fp_line
			(start 0.67945 -0.305054)
			(end 0.12065 -0.305054)
			(stroke
				(width 0.1)
				(type default)
			)
			(layer "B.Fab")
		)
		(fp_line
			(start 0.67945 0.3048)
			(end 0.67945 -0.305054)
			(stroke
				(width 0.1)
				(type default)
			)
			(layer "B.Fab")
		)
		(pad "1" smd circle
			(at 0.40005 0 180)
			(size 0 0)
			(layers "B.Cu" "B.Mask" "B.Paste")
			(net "P3V3_RGM")
		)
		(pad "2" smd circle
			(at -0.40005 0 180)
			(size 0 0)
			(layers "B.Cu" "B.Mask" "B.Paste")
			(net "GND")
		)
	)
	(footprint ""
		(layer "B.Cu")
		(at 44.0944 -62.0014 -90)
		(property "Reference" "R22"
			(at 0 0 90)
			(layer "B.SilkS")
			(hide yes)
			(effects
				(font
					(size 1.27 1.27)
				)
				(justify mirror)
			)
		)
		(property "Value" ""
			(at 0 0 90)
			(layer "B.Fab")
			(effects
				(font
					(size 1.27 1.27)
				)
				(justify mirror)
			)
		)
		(duplicate_pad_numbers_are_jumpers no)
		(fp_line
			(start -0.7874 0.4064)
			(end 0.7874 0.4064)
			(stroke
				(width 0.1524)
				(type default)
			)
			(layer "B.SilkS")
		)
		(fp_line
			(start 0.7874 0.4064)
			(end 0.7874 -0.4064)
			(stroke
				(width 0.1524)
				(type default)
			)
			(layer "B.SilkS")
		)
		(fp_line
			(start -0.7874 -0.4064)
			(end -0.7874 0.4064)
			(stroke
				(width 0.1524)
				(type default)
			)
			(layer "B.SilkS")
		)
		(fp_line
			(start 0.7874 -0.4064)
			(end -0.7874 -0.4064)
			(stroke
				(width 0.1524)
				(type default)
			)
			(layer "B.SilkS")
		)
		(fp_line
			(start -0.67945 0.3048)
			(end -0.120396 0.3048)
			(stroke
				(width 0.1)
				(type default)
			)
			(layer "B.Fab")
		)
		(fp_line
			(start -0.120396 0.3048)
			(end -0.120396 0.2794)
			(stroke
				(width 0.1)
				(type default)
			)
			(layer "B.Fab")
		)
		(fp_line
			(start 0.12065 0.3048)
			(end 0.67945 0.3048)
			(stroke
				(width 0.1)
				(type default)
			)
			(layer "B.Fab")
		)
		(fp_line
			(start 0.67945 0.3048)
			(end 0.67945 -0.305054)
			(stroke
				(width 0.1)
				(type default)
			)
			(layer "B.Fab")
		)
		(fp_line
			(start -0.120396 0.2794)
			(end 0.12065 0.2794)
			(stroke
				(width 0.1)
				(type default)
			)
			(layer "B.Fab")
		)
		(fp_line
			(start 0.12065 0.2794)
			(end 0.12065 0.3048)
			(stroke
				(width 0.1)
				(type default)
			)
			(layer "B.Fab")
		)
		(fp_line
			(start -0.12065 -0.2794)
			(end -0.12065 -0.3048)
			(stroke
				(width 0.1)
				(type default)
			)
			(layer "B.Fab")
		)
		(fp_line
			(start 0.12065 -0.2794)
			(end -0.12065 -0.2794)
			(stroke
				(width 0.1)
				(type default)
			)
			(layer "B.Fab")
		)
		(fp_line
			(start -0.67945 -0.3048)
			(end -0.67945 0.3048)
			(stroke
				(width 0.1)
				(type default)
			)
			(layer "B.Fab")
		)
		(fp_line
			(start -0.12065 -0.3048)
			(end -0.67945 -0.3048)
			(stroke
				(width 0.1)
				(type default)
			)
			(layer "B.Fab")
		)
		(fp_line
			(start 0.12065 -0.305054)
			(end 0.12065 -0.2794)
			(stroke
				(width 0.1)
				(type default)
			)
			(layer "B.Fab")
		)
		(fp_line
			(start 0.67945 -0.305054)
			(end 0.12065 -0.305054)
			(stroke
				(width 0.1)
				(type default)
			)
			(layer "B.Fab")
		)
		(pad "1" smd circle
			(at 0.40005 0 90)
			(size 0 0)
			(layers "B.Cu" "B.Mask" "B.Paste")
			(net "V_DACB_R")
		)
		(pad "2" smd circle
			(at -0.40005 0 90)
			(size 0 0)
			(layers "B.Cu" "B.Mask" "B.Paste")
			(net "GND")
		)
	)
	(footprint ""
		(layer "B.Cu")
		(at 7.838186 -3.639312)
		(property "Reference" ""
			(at 0 0 0)
			(layer "B.SilkS")
			(hide yes)
			(effects
				(font
					(size 1.27 1.27)
				)
				(justify mirror)
			)
		)
		(property "Value" ""
			(at 0 0 0)
			(layer "B.Fab")
			(effects
				(font
					(size 1.27 1.27)
				)
				(justify mirror)
			)
		)
		(duplicate_pad_numbers_are_jumpers no)
		(pad "1" smd circle
			(at 0 0 180)
			(size 0.9906 0.9906)
			(layers "B.Cu" "B.Mask" "B.Paste")
			(net "Net_135")
		)
		(zone
			(layer "B.Cu")
			(hatch none 0.5)
			(connect_pads
				(clearance 0)
			)
			(min_thickness 0.25)
			(keepout
				(tracks not_allowed)
				(vias allowed)
				(pads allowed)
				(copperpour not_allowed)
				(footprints allowed)
			)
			(placement
				(enabled no)
				(sheetname "")
			)
			(fill
				(thermal_gap 0.5)
				(thermal_bridge_width 0.5)
				(island_removal_mode 0)
			)
			(polygon
				(pts
					(arc
						(start 9.463786 -3.639312)
						(mid 6.212586 -3.639312)
						(end 9.463786 -3.639312)
					)
				)
			)
		)
	)
)
